# TIMECARD (Time Appliance Project (Time Card)) — schematic netlist excerpt (pin names and nets, part order shuffled) for the footprints in the layout excerpt that follows; sources: Cadence DE-HDL packaged netlist, KiCad conversion of R4006-B0001-02_R01.brd

CR5  DIODE_4_V1  pkg SOT143  page 23
  GND  = SG
  IO1  = SMA4_SIG_IO_CONN
  IO2  = SMA3_SIG_IO_CONN
  VDD  = NC

(kicad_pcb
	(version 20260206)
	(generator "pcbnew")
	(generator_version "10.0")
	(general
		(thickness 1.6)
		(legacy_teardrops no)
	)
	(paper "A4")
	(title_block
		(title "timecard-production-celestica-r4006 — R4006-B0001-02_R01.brd")
		(comment 1 "Time Appliance Project (Time Card) / footprints 41-41 of 1113")
	)
	(layers
		(0 "F.Cu" signal "TOP")
		(4 "In1.Cu" signal "L02_GND1")
		(6 "In2.Cu" signal "L03_SIG1")
		(8 "In3.Cu" signal "L04_GND2")
		(10 "In4.Cu" signal "L05_VCC1")
		(12 "In5.Cu" signal "L06_VCC2")
		(14 "In6.Cu" signal "L07_GND3")
		(16 "In7.Cu" signal "L08_SIG2")
		(18 "In8.Cu" signal "L09_GND4")
		(2 "B.Cu" signal "BOTTOM")
		(9 "F.Adhes" user "F.Adhesive")
		(11 "B.Adhes" user "B.Adhesive")
		(13 "F.Paste" user "Package Geometry/Pastemask Top")
		(15 "B.Paste" user "Package Geometry/Pastemask Bottom")
		(5 "F.SilkS" user "Ref Des/Silkscreen Top")
		(7 "B.SilkS" user "Ref Des/Silkscreen Bottom")
		(1 "F.Mask" user "Board Geometry/Soldermask Top")
		(3 "B.Mask" user "Board Geometry/Soldermask Bottom")
		(17 "Dwgs.User" user "User.Drawings")
		(19 "Cmts.User" user "User.Comments")
		(21 "Eco1.User" user "User.Eco1")
		(23 "Eco2.User" user "User.Eco2")
		(25 "Edge.Cuts" user "Board Geometry/Outline")
		(27 "Margin" user)
		(31 "F.CrtYd" user "Package Geometry/Place Bound Top")
		(29 "B.CrtYd" user "Package Geometry/Place Bound Bottom")
		(35 "F.Fab" user "Ref Des/Assembly Top")
		(33 "B.Fab" user "Ref Des/Assembly Bottom")
	)
	(footprint ""
		(layer "F.Cu")
		(at 5.969 -25.4 90)
		(property "Reference" "CR5"
			(at -0.508 2.32537 90)
			(unlocked yes)
			(layer "F.SilkS")
			(effects
				(font
					(size 0.7874 0.5842)
					(thickness 0.1524)
				)
			)
		)
		(property "Value" ""
			(at 0 0 90)
			(layer "F.Fab")
			(effects
				(font
					(size 1.27 1.27)
				)
			)
		)
		(property "User Part Number" "PARTNUM*"
			(at 0.254 3.718306 90)
			(unlocked yes)
			(layer "Cmts.User")
			(hide yes)
			(effects
				(font
					(size 0.7874 0.5842)
					(thickness 0.1524)
				)
			)
		)
		(property "Device Type" "DIODE_4_V1-G122-10123-01"
			(at 0.254 2.702306 90)
			(unlocked yes)
			(layer "F.Fab")
			(hide yes)
			(effects
				(font
					(size 0.7874 0.5842)
					(thickness 0.1524)
				)
			)
		)
		(duplicate_pad_numbers_are_jumpers no)
		(fp_line
			(start 2.0828 -1.7018)
			(end 2.0828 1.7018)
			(stroke
				(width 0.1)
				(type default)
			)
			(layer "F.SilkS")
		)
		(fp_line
			(start -2.0828 -1.7018)
			(end 2.0828 -1.7018)
			(stroke
				(width 0.1)
				(type default)
			)
			(layer "F.SilkS")
		)
		(fp_line
			(start 2.0828 1.7018)
			(end -2.0828 1.7018)
			(stroke
				(width 0.1)
				(type default)
			)
			(layer "F.SilkS")
		)
		(fp_line
			(start -2.0828 1.7018)
			(end -2.0828 -1.7018)
			(stroke
				(width 0.1)
				(type default)
			)
			(layer "F.SilkS")
		)
		(fp_poly
			(pts
				(arc
					(start -2.6162 -0.508)
					(mid -2.6162 -1.27)
					(end -2.6162 -0.508)
				)
			)
			(stroke
				(width 0)
				(type default)
			)
			(fill yes)
			(layer "F.SilkS")
		)
		(fp_rect
			(start -2.3368 -1.9304)
			(end 2.3368 1.9304)
			(stroke
				(width 0)
				(type default)
			)
			(fill no)
			(layer "F.CrtYd")
		)
		(fp_line
			(start 0.6477 -1.42875)
			(end 0.6477 1.42875)
			(stroke
				(width 0.1)
				(type default)
			)
			(layer "F.Fab")
		)
		(fp_line
			(start -0.6477 -1.42875)
			(end 0.6477 -1.42875)
			(stroke
				(width 0.1)
				(type default)
			)
			(layer "F.Fab")
		)
		(fp_line
			(start 1.143 -1.1811)
			(end 1.143 -0.7239)
			(stroke
				(width 0.1)
				(type default)
			)
			(layer "F.Fab")
		)
		(fp_line
			(start 0.6477 -1.1811)
			(end 1.143 -1.1811)
			(stroke
				(width 0.1)
				(type default)
			)
			(layer "F.Fab")
		)
		(fp_line
			(start -0.6477 -1.1811)
			(end -0.6477 -0.3175)
			(stroke
				(width 0.1)
				(type default)
			)
			(layer "F.Fab")
		)
		(fp_line
			(start -1.143 -1.1811)
			(end -0.6477 -1.1811)
			(stroke
				(width 0.1)
				(type default)
			)
			(layer "F.Fab")
		)
		(fp_line
			(start 1.143 -0.7239)
			(end 0.6477 -0.7239)
			(stroke
				(width 0.1)
				(type default)
			)
			(layer "F.Fab")
		)
		(fp_line
			(start 0.6477 -0.7239)
			(end 0.6477 -1.1811)
			(stroke
				(width 0.1)
				(type default)
			)
			(layer "F.Fab")
		)
		(fp_line
			(start -0.6477 -0.3175)
			(end -1.143 -0.3175)
			(stroke
				(width 0.1)
				(type default)
			)
			(layer "F.Fab")
		)
		(fp_line
			(start -1.143 -0.3175)
			(end -1.143 -1.1811)
			(stroke
				(width 0.1)
				(type default)
			)
			(layer "F.Fab")
		)
		(fp_line
			(start 1.143 0.7239)
			(end 1.143 1.1811)
			(stroke
				(width 0.1)
				(type default)
			)
			(layer "F.Fab")
		)
		(fp_line
			(start 0.6477 0.7239)
			(end 1.143 0.7239)
			(stroke
				(width 0.1)
				(type default)
			)
			(layer "F.Fab")
		)
		(fp_line
			(start -0.6477 0.7239)
			(end -0.6477 1.1811)
			(stroke
				(width 0.1)
				(type default)
			)
			(layer "F.Fab")
		)
		(fp_line
			(start -1.143 0.7239)
			(end -0.6477 0.7239)
			(stroke
				(width 0.1)
				(type default)
			)
			(layer "F.Fab")
		)
		(fp_line
			(start 1.143 1.1811)
			(end 0.6477 1.1811)
			(stroke
				(width 0.1)
				(type default)
			)
			(layer "F.Fab")
		)
		(fp_line
			(start 0.6477 1.1811)
			(end 0.6477 0.7239)
			(stroke
				(width 0.1)
				(type default)
			)
			(layer "F.Fab")
		)
		(fp_line
			(start -0.6477 1.1811)
			(end -1.143 1.1811)
			(stroke
				(width 0.1)
				(type default)
			)
			(layer "F.Fab")
		)
		(fp_line
			(start -1.143 1.1811)
			(end -1.143 0.7239)
			(stroke
				(width 0.1)
				(type default)
			)
			(layer "F.Fab")
		)
		(fp_line
			(start 0.6477 1.42875)
			(end -0.6477 1.42875)
			(stroke
				(width 0.1)
				(type default)
			)
			(layer "F.Fab")
		)
		(fp_line
			(start -0.6477 1.42875)
			(end -0.6477 -1.42875)
			(stroke
				(width 0.1)
				(type default)
			)
			(layer "F.Fab")
		)
		(fp_poly
			(pts
				(arc
					(start -0.381 -0.5588)
					(mid -0.381 -0.9398)
					(end -0.381 -0.5588)
				)
			)
			(stroke
				(width 0)
				(type default)
			)
			(fill yes)
			(layer "F.Fab")
		)
		(fp_text user "4"
			(at 2.510028 -1.311656 0)
			(unlocked yes)
			(layer "F.SilkS")
			(effects
				(font
					(size 0.635 0.4064)
					(thickness 0.1524)
				)
				(justify left)
			)
		)
		(fp_text user "3"
			(at 2.50825 1.4478 0)
			(unlocked yes)
			(layer "F.SilkS")
			(effects
				(font
					(size 0.635 0.4064)
					(thickness 0.1524)
				)
				(justify left)
			)
		)
		(fp_text user "2"
			(at -2.44475 1.8288 0)
			(unlocked yes)
			(layer "F.SilkS")
			(effects
				(font
					(size 0.635 0.4064)
					(thickness 0.1524)
				)
				(justify left)
			)
		)
		(fp_text user "4"
			(at 1.829308 -1.273556 0)
			(unlocked yes)
			(layer "F.Fab")
			(effects
				(font
					(size 0.7874 0.5842)
					(thickness 0.1524)
				)
				(justify left)
			)
		)
		(fp_text user "2"
			(at -1.81737 0.7239 0)
			(unlocked yes)
			(layer "F.Fab")
			(effects
				(font
					(size 0.7874 0.5842)
					(thickness 0.1524)
				)
				(justify left)
			)
		)
		(fp_text user "3"
			(at 1.829308 0.758444 0)
			(unlocked yes)
			(layer "F.Fab")
			(effects
				(font
					(size 0.7874 0.5842)
					(thickness 0.1524)
				)
				(justify left)
			)
		)
		(pad "1" smd rect
			(at -1.1049 -0.7493 90)
			(size 1.4478 1.0922)
			(layers "F.Cu" "F.Mask" "F.Paste")
			(net "SG")
		)
		(pad "2" smd rect
			(at -1.1049 0.9525 90)
			(size 1.4478 0.9906)
			(layers "F.Cu" "F.Mask" "F.Paste")
			(net "SMA4_SIG_IO_CONN")
		)
		(pad "3" smd rect
			(at 1.1049 0.9525 90)
			(size 1.4478 0.9906)
			(layers "F.Cu" "F.Mask" "F.Paste")
			(net "SMA3_SIG_IO_CONN")
		)
		(pad "4" smd rect
			(at 1.1049 -0.9525 90)
			(size 1.4478 0.9906)
			(layers "F.Cu" "F.Mask" "F.Paste")
			(net "Net_566")
		)
		(zone
			(layer "F.Cu")
			(hatch none 0.5)
			(connect_pads
				(clearance 0)
			)
			(min_thickness 0.25)
			(keepout
				(tracks allowed)
				(vias not_allowed)
				(pads allowed)
				(copperpour not_allowed)
				(footprints allowed)
			)
			(placement
				(enabled no)
				(sheetname "")
			)
			(fill
				(thermal_gap 0.5)
				(thermal_bridge_width 0.5)
				(island_removal_mode 0)
			)
			(polygon
				(pts
					(xy 4.6736 -24.7523) (xy 4.5339 -24.7523) (xy 4.5339 -25.781) (xy 5.5118 -25.781) (xy 5.5118 -26.0477)
					(xy 6.4262 -26.0477) (xy 6.4262 -25.781) (xy 7.4041 -25.781) (xy 7.4041 -25.019) (xy 6.4262 -25.019)
					(xy 6.4262 -24.7523) (xy 5.7658 -24.7523) (xy 5.7658 -25.019) (xy 4.6736 -25.019)
				)
			)
		)
	)
)
